# BASEBOARD_FAB2 (Tioga Pass) — schematic netlist excerpt (pin names and nets, part order shuffled) for the footprints in the layout excerpt that follows; sources: Cadence DE-HDL packaged netlist, KiCad conversion of Wiwynn_Tioga_Pass_MB.brd

R4P10  RES  90.9 1% CHIP  pkg 0402  page 21 : A = A_CPU0_ABC_RCOMP1 ; B = GND
R30W3  RES  0.0 5% CHIP  pkg 0402  page 253 : A = USB3_P01_C_TXN ; B = USB3_P01_FB_TXN
C4P5  CAP  100UF 4V 20% X5R  pkg 0805  page 42 : A = PVCCMCP_CPU0 ; B = GND

(kicad_pcb
	(version 20260206)
	(generator "pcbnew")
	(generator_version "10.0")
	(general
		(thickness 1.6)
		(legacy_teardrops no)
	)
	(paper "A4")
	(title_block
		(title "Wiwynn_Tioga_Pass_MB.brd")
		(comment 1 "Tioga Pass / footprints 4173-4175 of 4770")
	)
	(layers
		(0 "F.Cu" signal "TOP")
		(4 "In1.Cu" signal "L2GND")
		(6 "In2.Cu" signal "L3")
		(8 "In3.Cu" signal "L4GND")
		(10 "In4.Cu" signal "L5")
		(12 "In5.Cu" signal "L6GND")
		(14 "In6.Cu" signal "L7VCC")
		(16 "In7.Cu" signal "L8VCC")
		(18 "In8.Cu" signal "L9GND")
		(20 "In9.Cu" signal "L10")
		(22 "In10.Cu" signal "L11GND")
		(24 "In11.Cu" signal "L12")
		(26 "In12.Cu" signal "L13GND")
		(2 "B.Cu" signal "BOTTOM")
		(9 "F.Adhes" user "F.Adhesive")
		(11 "B.Adhes" user "B.Adhesive")
		(13 "F.Paste" user "Package Geometry/Pastemask Top")
		(15 "B.Paste" user "Package Geometry/Pastemask Bottom")
		(5 "F.SilkS" user "Ref Des/Silkscreen Top")
		(7 "B.SilkS" user "Ref Des/Silkscreen Bottom")
		(1 "F.Mask" user "Board Geometry/Soldermask Top")
		(3 "B.Mask" user "Board Geometry/Soldermask Bottom")
		(17 "Dwgs.User" user "User.Drawings")
		(19 "Cmts.User" user "User.Comments")
		(21 "Eco1.User" user "User.Eco1")
		(23 "Eco2.User" user "User.Eco2")
		(25 "Edge.Cuts" user "Board Geometry/Outline")
		(27 "Margin" user)
		(31 "F.CrtYd" user "Package Geometry/Place Bound Top")
		(29 "B.CrtYd" user "Package Geometry/Place Bound Bottom")
		(35 "F.Fab" user "Ref Des/Assembly Top")
		(33 "B.Fab" user "Ref Des/Assembly Bottom")
	)
	(footprint ""
		(layer "B.Cu")
		(at 488.22991 -60.818014 90)
		(property "Reference" "R30W3"
			(at 0.8382 -0.67818 90)
			(unlocked yes)
			(layer "B.SilkS")
			(effects
				(font
					(size 0.4064 0.254)
					(thickness 0.1524)
				)
				(justify left mirror)
			)
		)
		(property "Value" ""
			(at 0 0 90)
			(layer "B.Fab")
			(effects
				(font
					(size 1.27 1.27)
				)
				(justify mirror)
			)
		)
		(duplicate_pad_numbers_are_jumpers no)
		(fp_poly
			(pts
				(xy 0.2794 -0.1016) (xy -0.2794 -0.1016) (xy -0.2794 0.9906) (xy 0.2794 0.9906)
			)
			(stroke
				(width 0)
				(type default)
			)
			(fill no)
			(layer "B.CrtYd")
		)
		(fp_line
			(start 0.2794 -0.1016)
			(end 0.2794 0.9906)
			(stroke
				(width 0.1)
				(type default)
			)
			(layer "B.Fab")
		)
		(fp_line
			(start -0.2794 -0.1016)
			(end 0.2794 -0.1016)
			(stroke
				(width 0.1)
				(type default)
			)
			(layer "B.Fab")
		)
		(fp_line
			(start 0.2794 0.9906)
			(end -0.2794 0.9906)
			(stroke
				(width 0.1)
				(type default)
			)
			(layer "B.Fab")
		)
		(fp_line
			(start -0.2794 0.9906)
			(end -0.2794 -0.1016)
			(stroke
				(width 0.1)
				(type default)
			)
			(layer "B.Fab")
		)
		(pad "1" smd rect
			(at 0 0 270)
			(size 0.508 0.508)
			(layers "B.Cu" "B.Mask" "B.Paste")
			(net "USB3_P01_C_TXN")
		)
		(pad "2" smd rect
			(at 0 0.889 270)
			(size 0.508 0.508)
			(layers "B.Cu" "B.Mask" "B.Paste")
			(net "USB3_P01_FB_TXN")
		)
		(zone
			(layer "B.Cu")
			(hatch none 0.5)
			(connect_pads
				(clearance 0)
			)
			(min_thickness 0.25)
			(keepout
				(tracks allowed)
				(vias not_allowed)
				(pads allowed)
				(copperpour not_allowed)
				(footprints allowed)
			)
			(placement
				(enabled no)
				(sheetname "")
			)
			(fill
				(thermal_gap 0.5)
				(thermal_bridge_width 0.5)
				(island_removal_mode 0)
			)
			(polygon
				(pts
					(xy 488.48391 -61.072014) (xy 488.48391 -60.564014) (xy 488.86491 -60.564014) (xy 488.86491 -61.072014)
				)
			)
		)
		(zone
			(layer "B.Cu")
			(hatch none 0.5)
			(connect_pads
				(clearance 0)
			)
			(min_thickness 0.25)
			(keepout
				(tracks not_allowed)
				(vias allowed)
				(pads allowed)
				(copperpour not_allowed)
				(footprints allowed)
			)
			(placement
				(enabled no)
				(sheetname "")
			)
			(fill
				(thermal_gap 0.5)
				(thermal_bridge_width 0.5)
				(island_removal_mode 0)
			)
			(polygon
				(pts
					(xy 488.86491 -61.072014) (xy 488.86491 -60.564014) (xy 488.48391 -60.564014) (xy 488.48391 -61.072014)
				)
			)
		)
	)
	(footprint ""
		(layer "B.Cu")
		(at 282.259024 -72.679814 -90)
		(property "Reference" "R4P10"
			(at 0 0 90)
			(layer "B.SilkS")
			(hide yes)
			(effects
				(font
					(size 1.27 1.27)
				)
				(justify mirror)
			)
		)
		(property "Value" ""
			(at 0 0 90)
			(layer "B.Fab")
			(effects
				(font
					(size 1.27 1.27)
				)
				(justify mirror)
			)
		)
		(duplicate_pad_numbers_are_jumpers no)
		(fp_rect
			(start 0.2794 0.9906)
			(end -0.2794 -0.1016)
			(stroke
				(width 0)
				(type default)
			)
			(fill no)
			(layer "B.CrtYd")
		)
		(fp_line
			(start -0.2794 0.9906)
			(end -0.2794 -0.1016)
			(stroke
				(width 0.1)
				(type default)
			)
			(layer "B.Fab")
		)
		(fp_line
			(start 0.2794 0.9906)
			(end -0.2794 0.9906)
			(stroke
				(width 0.1)
				(type default)
			)
			(layer "B.Fab")
		)
		(fp_line
			(start -0.2794 -0.1016)
			(end 0.2794 -0.1016)
			(stroke
				(width 0.1)
				(type default)
			)
			(layer "B.Fab")
		)
		(fp_line
			(start 0.2794 -0.1016)
			(end 0.2794 0.9906)
			(stroke
				(width 0.1)
				(type default)
			)
			(layer "B.Fab")
		)
		(pad "1" smd rect
			(at 0 0 90)
			(size 0.508 0.508)
			(layers "B.Cu" "B.Mask" "B.Paste")
			(net "A_CPU0_ABC_RCOMP1")
		)
		(pad "2" smd rect
			(at 0 0.889 90)
			(size 0.508 0.508)
			(layers "B.Cu" "B.Mask" "B.Paste")
			(net "GND")
		)
		(zone
			(layer "B.Cu")
			(hatch none 0.5)
			(connect_pads
				(clearance 0)
			)
			(min_thickness 0.25)
			(keepout
				(tracks allowed)
				(vias not_allowed)
				(pads allowed)
				(copperpour not_allowed)
				(footprints allowed)
			)
			(placement
				(enabled no)
				(sheetname "")
			)
			(fill
				(thermal_gap 0.5)
				(thermal_bridge_width 0.5)
				(island_removal_mode 0)
			)
			(polygon
				(pts
					(xy 281.624024 -72.425814) (xy 282.005024 -72.425814) (xy 282.005024 -72.933814) (xy 281.624024 -72.933814)
				)
			)
		)
		(zone
			(layer "B.Cu")
			(hatch none 0.5)
			(connect_pads
				(clearance 0)
			)
			(min_thickness 0.25)
			(keepout
				(tracks not_allowed)
				(vias allowed)
				(pads allowed)
				(copperpour not_allowed)
				(footprints allowed)
			)
			(placement
				(enabled no)
				(sheetname "")
			)
			(fill
				(thermal_gap 0.5)
				(thermal_bridge_width 0.5)
				(island_removal_mode 0)
			)
			(polygon
				(pts
					(xy 281.624024 -72.425814) (xy 282.005024 -72.425814) (xy 282.005024 -72.933814) (xy 281.624024 -72.933814)
				)
			)
		)
	)
	(footprint ""
		(layer "B.Cu")
		(at 278.703024 -77.810614)
		(property "Reference" "C4P5"
			(at 0 0 0)
			(layer "B.SilkS")
			(hide yes)
			(effects
				(font
					(size 1.27 1.27)
				)
				(justify mirror)
			)
		)
		(property "Value" ""
			(at 0 0 0)
			(layer "B.Fab")
			(effects
				(font
					(size 1.27 1.27)
				)
				(justify mirror)
			)
		)
		(duplicate_pad_numbers_are_jumpers no)
		(fp_poly
			(pts
				(xy 0.7239 -0.2159) (xy -0.7239 -0.2159) (xy -0.7239 1.9939) (xy 0.7239 1.9939)
			)
			(stroke
				(width 0)
				(type default)
			)
			(fill no)
			(layer "B.CrtYd")
		)
		(fp_line
			(start -0.7239 -0.2159)
			(end 0.7239 -0.2159)
			(stroke
				(width 0.1)
				(type default)
			)
			(layer "B.Fab")
		)
		(fp_line
			(start -0.7239 1.9939)
			(end -0.7239 -0.2159)
			(stroke
				(width 0.1)
				(type default)
			)
			(layer "B.Fab")
		)
		(fp_line
			(start 0.7239 -0.2159)
			(end 0.7239 1.9939)
			(stroke
				(width 0.1)
				(type default)
			)
			(layer "B.Fab")
		)
		(fp_line
			(start 0.7239 1.9939)
			(end -0.7239 1.9939)
			(stroke
				(width 0.1)
				(type default)
			)
			(layer "B.Fab")
		)
		(pad "1" smd rect
			(at 0 0 180)
			(size 1.27 1.016)
			(layers "B.Cu" "B.Mask" "B.Paste")
			(net "PVCCMCP_CPU0")
		)
		(pad "2" smd rect
			(at 0 1.778 180)
			(size 1.27 1.016)
			(layers "B.Cu" "B.Mask" "B.Paste")
			(net "GND")
		)
		(zone
			(layer "B.Cu")
			(hatch none 0.5)
			(connect_pads
				(clearance 0)
			)
			(min_thickness 0.25)
			(keepout
				(tracks not_allowed)
				(vias allowed)
				(pads allowed)
				(copperpour not_allowed)
				(footprints allowed)
			)
			(placement
				(enabled no)
				(sheetname "")
			)
			(fill
				(thermal_gap 0.5)
				(thermal_bridge_width 0.5)
				(island_removal_mode 0)
			)
			(polygon
				(pts
					(xy 279.338024 -77.302614) (xy 278.068024 -77.302614) (xy 278.068024 -76.540614) (xy 279.338024 -76.540614)
				)
			)
		)
	)
)
